FILE_TYPE = MACRO_DRAWING;
SET COLOR_WIRE YELLOW;
SET COLOR_PROP ORANGE;
SET COLOR_DOT WHITE;
SET COLOR_ARC YELLOW;
SET COLOR_BODY GREEN;
SET COLOR_NOTE PURPLE;
SET PROP_DISPLAY VALUE;
SET PAGE_NUMBER P156;
FORCEADD CONN3_G800LQ305005FTHR..1
R 6
(-1500 7575);
FORCEPROP 1 LAST LOCATION JP12
J 0
(-1550 7800);
DISPLAY 0.489362 (-1550 7800);
PAINT SKYBLUE (-1550 7800);
FORCEPROP 0 LAST $SEC 1
J 0
(-1550 8000);
DISPLAY 0.680851 (-1550 8000);
PAINT MONO (-1550 8000);
DISPLAY INVISIBLE (-1550 8000);
FORCEPROP 2 LAST CDS_SEC 1
J 2
(-1325 7127);
DISPLAY 1.021277 (-1325 7127);
DISPLAY INVISIBLE (-1325 7127);
FORCEPROP 0 LASTPIN (-1700 7625) $PN 1
J 2
(-1710 7635);
DISPLAY 0.489362 (-1710 7635);
PAINT MONO (-1710 7635);
FORCEPROP 0 LASTPIN (-1700 7575) $PN 2
J 2
(-1710 7585);
DISPLAY 0.489362 (-1710 7585);
PAINT MONO (-1710 7585);
FORCEPROP 0 LASTPIN (-1700 7525) $PN 3
J 2
(-1710 7535);
DISPLAY 0.489362 (-1710 7535);
PAINT MONO (-1710 7535);
FORCEPROP 2 LAST PART_TYPE THLF
J 0
(-1550 7708);
DISPLAY 0.638298 (-1550 7708);
FORCEPROP 1 LAST MATERIAL IO
J 0
(-1550 7950);
DISPLAY 0.489362 (-1550 7950);
PAINT SKYBLUE (-1550 7950);
FORCEPROP 2 LAST VALUE CONN3_G800LQ305005FTHR
J 0
(-1550 7765);
DISPLAY 0.489362 (-1550 7765);
PAINT SKYBLUE (-1550 7765);
FORCEPROP 1 LAST PART_NUMBER DFHD03MS403
J 0
(-1550 7875);
DISPLAY 0.489362 (-1550 7875);
PAINT SKYBLUE (-1550 7875);
FORCEPROP 1 LAST NEEDS_NO_SIZE TRUE
J 0
(-1500 7541);
DISPLAY 0.723404 (-1500 7541);
PAINT GREEN (-1500 7541);
DISPLAY INVISIBLE (-1500 7541);
FORCEPROP 2 LAST CDS_LIB pure_quanta
J 0
(-1500 7528);
DISPLAY INVISIBLE (-1500 7528);
FORCEPROP 1 LAST CDS_LMAN_SYM_OUTLINE -50,100,50,-100
J 0
(-1500 7553);
DISPLAY 0.468085 (-1500 7553);
PAINT GREEN (-1500 7553);
DISPLAY INVISIBLE (-1500 7553);
FORCEPROP 1 LAST PATH I1
J 0
(-1500 7541);
DISPLAY 0.723404 (-1500 7541);
PAINT GREEN (-1500 7541);
DISPLAY INVISIBLE (-1500 7541);
FORCEADD Q_RES..1
(-2875 5675);
FORCEPROP 1 LAST LOCATION R1779
J 0
(-3175 5675);
DISPLAY 0.489362 (-3175 5675);
PAINT SKYBLUE (-3175 5675);
FORCEPROP 0 LAST $SEC 1
J 0
(-2600 5725);
DISPLAY 0.680851 (-2600 5725);
PAINT MONO (-2600 5725);
DISPLAY INVISIBLE (-2600 5725);
FORCEPROP 0 LAST CDS_SEC 1
J 0
(-2600 5725);
DISPLAY 1.021277 (-2600 5725);
DISPLAY INVISIBLE (-2600 5725);
FORCEPROP 1 LASTPIN (-2975 5675) $PN 1
J 0
(-2963 5687);
DISPLAY 0.489362 (-2963 5687);
PAINT MONO (-2963 5687);
FORCEPROP 1 LASTPIN (-2775 5675) $PN 2
J 0
(-2813 5687);
DISPLAY 0.489362 (-2813 5687);
PAINT MONO (-2813 5687);
FORCEPROP 1 LAST WATTAGE 1/16W
J 2
(-2575 5600);
DISPLAY 0.489362 (-2575 5600);
PAINT SKYBLUE (-2575 5600);
FORCEPROP 1 LAST MATERIAL CHIP
J 0
(-2600 5675);
DISPLAY 0.489362 (-2600 5675);
PAINT SKYBLUE (-2600 5675);
FORCEPROP 1 LAST TOLERANCE 1%
J 0
(-2675 5675);
DISPLAY 0.489362 (-2675 5675);
PAINT SKYBLUE (-2675 5675);
FORCEPROP 1 LAST VALUE 100
J 2
(-2700 5675);
DISPLAY 0.489362 (-2700 5675);
PAINT SKYBLUE (-2700 5675);
FORCEPROP 1 LAST PART_NUMBER TMP_QCS11002FB22
J 0
(-2950 5550);
DISPLAY 0.489362 (-2950 5550);
PAINT SKYBLUE (-2950 5550);
FORCEPROP 1 LAST PACK_TYPE 0402LF
J 0
(-2950 5600);
DISPLAY 0.489362 (-2950 5600);
PAINT SKYBLUE (-2950 5600);
FORCEPROP 2 LAST CDS_LIB pure_quanta
J 0
(-2875 5675);
DISPLAY INVISIBLE (-2875 5675);
FORCEPROP 1 LAST PATH I10
J 0
(-2925 5825);
DISPLAY 0.978723 (-2925 5825);
PAINT WHITE (-2925 5825);
DISPLAY INVISIBLE (-2925 5825);
FORCEADD UNIVERSAL_GND..1
R 2
(-1800 7300);
FORCEPROP 3 LASTPIN (-1800 7350) SIG_NAME GND\g
J 0
(-1790 7360);
DISPLAY 0.659574 (-1790 7360);
PAINT MONO (-1790 7360);
DISPLAY INVISIBLE (-1790 7360);
FORCEPROP 2 LAST CDS_LIB pure_quanta_power
J 2
(-1800 7300);
PAINT MONO (-1800 7300);
DISPLAY INVISIBLE (-1800 7300);
FORCEPROP 1 LAST PATH I2
J 2
(-1875 7300);
DISPLAY 0.872340 (-1875 7300);
PAINT AQUA (-1875 7300);
DISPLAY INVISIBLE (-1875 7300);
FORCEPROP 1 LAST HDL_POWER GND
J 1
(-1825 7225);
DISPLAY 0.872340 (-1825 7225);
PAINT GREEN (-1825 7225);
DISPLAY INVISIBLE (-1825 7225);
FORCEADD NCP698SQ15T1G..1
(-4200 6900);
FORCEPROP 1 LAST LOCATION U167
J 0
(-4400 7135);
DISPLAY 0.489362 (-4400 7135);
PAINT SKYBLUE (-4400 7135);
FORCEPROP 0 LAST $SEC 1
J 0
(-4400 7275);
DISPLAY 0.680851 (-4400 7275);
PAINT MONO (-4400 7275);
DISPLAY INVISIBLE (-4400 7275);
FORCEPROP 0 LAST CDS_SEC 1
J 0
(-4400 7275);
DISPLAY 1.021277 (-4400 7275);
DISPLAY INVISIBLE (-4400 7275);
FORCEPROP 0 LASTPIN (-3850 6825) $PN 4
J 0
(-3840 6835);
DISPLAY 0.489362 (-3840 6835);
PAINT MONO (-3840 6835);
FORCEPROP 0 LASTPIN (-4550 6825) $PN 1
J 2
(-4560 6835);
DISPLAY 0.489362 (-4560 6835);
PAINT MONO (-4560 6835);
FORCEPROP 0 LASTPIN (-4550 6975) $PN 2
J 2
(-4560 6985);
DISPLAY 0.489362 (-4560 6985);
PAINT MONO (-4560 6985);
FORCEPROP 0 LASTPIN (-3850 6975) $PN 3
J 0
(-3840 6985);
DISPLAY 0.489362 (-3840 6985);
PAINT MONO (-3840 6985);
FORCEPROP 2 LAST PART_TYPE SMLF
J 0
(-4400 7225);
DISPLAY 1.021277 (-4400 7225);
FORCEPROP 1 LAST MATERIAL IC
J 0
(-4400 7035);
DISPLAY 0.489362 (-4400 7035);
PAINT SKYBLUE (-4400 7035);
FORCEPROP 2 LAST VALUE NCP698SQ15T1G
J 0
(-4400 7175);
DISPLAY 0.489362 (-4400 7175);
PAINT SKYBLUE (-4400 7175);
FORCEPROP 1 LAST PART_NUMBER AL000698000
J 0
(-4400 7084);
DISPLAY 0.489362 (-4400 7084);
PAINT SKYBLUE (-4400 7084);
FORCEPROP 2 LAST CDS_LIB pure_quanta
J 0
(-4200 6900);
DISPLAY INVISIBLE (-4200 6900);
FORCEPROP 1 LAST CDS_LMAN_SYM_OUTLINE -200,125,200,-125
J 0
(-4200 6900);
DISPLAY 0.468085 (-4200 6900);
PAINT GREEN (-4200 6900);
DISPLAY INVISIBLE (-4200 6900);
FORCEPROP 1 LAST NEEDS_NO_SIZE TRUE
J 0
(-4200 6900);
DISPLAY 0.723404 (-4200 6900);
PAINT GREEN (-4200 6900);
DISPLAY INVISIBLE (-4200 6900);
FORCEPROP 1 LAST PATH I22
J 0
(-4200 6900);
DISPLAY 0.723404 (-4200 6900);
PAINT GREEN (-4200 6900);
DISPLAY INVISIBLE (-4200 6900);
FORCEADD UNIVERSAL_GND..1
(-4575 6575);
FORCEPROP 3 LASTPIN (-4575 6625) SIG_NAME GND\g
J 0
(-4565 6635);
DISPLAY 0.659574 (-4565 6635);
PAINT MONO (-4565 6635);
DISPLAY INVISIBLE (-4565 6635);
FORCEPROP 2 LAST CDS_LIB pure_quanta_power
J 0
(-4575 6575);
DISPLAY INVISIBLE (-4575 6575);
FORCEPROP 1 LAST PATH I23
J 0
(-4500 6575);
DISPLAY 0.872340 (-4500 6575);
PAINT AQUA (-4500 6575);
DISPLAY INVISIBLE (-4500 6575);
FORCEPROP 1 LAST HDL_POWER GND
J 1
(-4550 6500);
DISPLAY 0.872340 (-4550 6500);
PAINT GREEN (-4550 6500);
DISPLAY INVISIBLE (-4550 6500);
FORCEADD Q_RES..2
(-4725 6325);
FORCEPROP 1 LAST LOCATION R1777
J 0
(-4680 6450);
DISPLAY 0.489362 (-4680 6450);
PAINT SKYBLUE (-4680 6450);
FORCEPROP 0 LAST $SEC 1
J 0
(-4675 6500);
DISPLAY 0.680851 (-4675 6500);
PAINT MONO (-4675 6500);
DISPLAY INVISIBLE (-4675 6500);
FORCEPROP 0 LAST CDS_SEC 1
J 0
(-4675 6500);
DISPLAY 1.021277 (-4675 6500);
DISPLAY INVISIBLE (-4675 6500);
FORCEPROP 1 LASTPIN (-4725 6425) $PN 1
J 0
(-4720 6387);
DISPLAY 0.489362 (-4720 6387);
PAINT MONO (-4720 6387);
FORCEPROP 1 LASTPIN (-4725 6225) $PN 2
J 0
(-4720 6235);
DISPLAY 0.489362 (-4720 6235);
PAINT MONO (-4720 6235);
FORCEPROP 1 LAST WATTAGE 1/16W
J 0
(-4685 6300);
DISPLAY 0.489362 (-4685 6300);
PAINT SKYBLUE (-4685 6300);
FORCEPROP 1 LAST MATERIAL CHIP
J 0
(-4685 6250);
DISPLAY 0.489362 (-4685 6250);
PAINT SKYBLUE (-4685 6250);
FORCEPROP 1 LAST TOLERANCE 1%
J 0
(-4680 6350);
DISPLAY 0.489362 (-4680 6350);
PAINT SKYBLUE (-4680 6350);
FORCEPROP 1 LAST VALUE 1K
J 0
(-4680 6400);
DISPLAY 0.489362 (-4680 6400);
PAINT SKYBLUE (-4680 6400);
FORCEPROP 1 LAST PART_NUMBER TMP_QCS21002FB24
J 0
(-4685 6200);
DISPLAY 0.489362 (-4685 6200);
PAINT SKYBLUE (-4685 6200);
FORCEPROP 1 LAST PACK_TYPE 0402LF
J 0
(-4685 6150);
DISPLAY 0.489362 (-4685 6150);
PAINT SKYBLUE (-4685 6150);
FORCEPROP 2 LAST CDS_LIB pure_quanta
J 0
(-4725 6325);
DISPLAY INVISIBLE (-4725 6325);
FORCEPROP 1 LAST PATH I24
J 0
(-4675 6500);
DISPLAY 0.978723 (-4675 6500);
PAINT WHITE (-4675 6500);
DISPLAY INVISIBLE (-4675 6500);
FORCEADD UNIVERSAL_POWER..1
(-5850 7425);
FORCEPROP 3 LASTPIN (-5850 7375) SIG_NAME P3V3_RTC_AUX\g
J 0
(-5840 7385);
DISPLAY 0.659574 (-5840 7385);
PAINT MONO (-5840 7385);
DISPLAY INVISIBLE (-5840 7385);
FORCEPROP 1 LAST HDL_POWER P3V3_RTC_AUX
J 1
(-5850 7475);
DISPLAY 0.489362 (-5850 7475);
PAINT GREEN (-5850 7475);
FORCEPROP 2 LAST CDS_LIB pure_quanta_power
J 0
(-5850 7425);
DISPLAY INVISIBLE (-5850 7425);
FORCEPROP 1 LAST PATH I25
J 0
(-5800 7450);
DISPLAY 0.872340 (-5800 7450);
PAINT AQUA (-5800 7450);
DISPLAY INVISIBLE (-5800 7450);
FORCEADD Q_CAP..1
R 2
(-5600 6775);
FORCEPROP 1 LAST LOCATION C193
J 0
(-5525 6875);
DISPLAY 0.489362 (-5525 6875);
PAINT SKYBLUE (-5525 6875);
FORCEPROP 0 LAST $SEC 1
J 0
(-5650 6925);
PAINT MONO (-5650 6925);
DISPLAY INVISIBLE (-5650 6925);
FORCEPROP 0 LAST CDS_SEC 1
J 0
(-5650 6925);
PAINT MONO (-5650 6925);
DISPLAY INVISIBLE (-5650 6925);
FORCEPROP 1 LASTPIN (-5600 6875) $PN 1
J 2
(-5610 6855);
DISPLAY 0.489362 (-5610 6855);
PAINT GREEN (-5610 6855);
FORCEPROP 1 LASTPIN (-5600 6675) $PN 2
J 2
(-5610 6655);
DISPLAY 0.489362 (-5610 6655);
PAINT GREEN (-5610 6655);
FORCEPROP 1 LAST MATERIAL X7R
J 0
(-5525 6675);
DISPLAY 0.489362 (-5525 6675);
PAINT SKYBLUE (-5525 6675);
FORCEPROP 1 LAST TOLERANCE 10%
J 0
(-5525 6725);
DISPLAY 0.489362 (-5525 6725);
PAINT SKYBLUE (-5525 6725);
FORCEPROP 1 LAST VALUE 100NF
J 0
(-5525 6825);
DISPLAY 0.489362 (-5525 6825);
PAINT SKYBLUE (-5525 6825);
FORCEPROP 1 LAST PART_NUMBER CH4106K1B01
J 2
(-5200 6625);
DISPLAY 0.489362 (-5200 6625);
PAINT SKYBLUE (-5200 6625);
FORCEPROP 1 LAST VOLTAGE 50V
J 0
(-5525 6775);
DISPLAY 0.489362 (-5525 6775);
PAINT SKYBLUE (-5525 6775);
FORCEPROP 1 LAST PACK_TYPE C0402
J 0
(-5525 6575);
DISPLAY 0.489362 (-5525 6575);
PAINT SKYBLUE (-5525 6575);
FORCEPROP 2 LAST CDS_LIB pure_quanta
J 0
(-5600 6775);
PAINT MONO (-5600 6775);
DISPLAY INVISIBLE (-5600 6775);
FORCEPROP 1 LAST PATH I26
J 2
(-5650 6925);
DISPLAY 0.978723 (-5650 6925);
PAINT WHITE (-5650 6925);
DISPLAY INVISIBLE (-5650 6925);
FORCEPROP 2 LAST ROOM MIO_LEGACY
J 0
(-5650 6975);
DISPLAY 1.021277 (-5650 6975);
PAINT RED (-5650 6975);
DISPLAY INVISIBLE (-5650 6975);
FORCEADD Q_CAP..1
(-6050 6775);
FORCEPROP 1 LAST LOCATION C45
J 0
(-6000 6875);
DISPLAY 0.489362 (-6000 6875);
PAINT SKYBLUE (-6000 6875);
FORCEPROP 2 LAST $SEC 1
J 0
(-6000 6975);
DISPLAY 0.680851 (-6000 6975);
PAINT MONO (-6000 6975);
DISPLAY INVISIBLE (-6000 6975);
FORCEPROP 2 LAST CDS_SEC 1
J 0
(-6000 6975);
DISPLAY 0.680851 (-6000 6975);
DISPLAY INVISIBLE (-6000 6975);
FORCEPROP 1 LASTPIN (-6050 6875) $PN 1
J 0
(-6040 6855);
DISPLAY 0.489362 (-6040 6855);
FORCEPROP 1 LASTPIN (-6050 6675) $PN 2
J 0
(-6040 6655);
DISPLAY 0.489362 (-6040 6655);
FORCEPROP 1 LAST MATERIAL X6S
J 0
(-6000 6675);
DISPLAY 0.489362 (-6000 6675);
PAINT SKYBLUE (-6000 6675);
FORCEPROP 1 LAST TOLERANCE 10%
J 0
(-6000 6725);
DISPLAY 0.489362 (-6000 6725);
PAINT SKYBLUE (-6000 6725);
FORCEPROP 1 LAST VALUE 1UF
J 0
(-6000 6825);
DISPLAY 0.489362 (-6000 6825);
PAINT SKYBLUE (-6000 6825);
FORCEPROP 1 LAST PART_NUMBER CH5104KEB02
J 0
(-6000 6625);
DISPLAY 0.489362 (-6000 6625);
PAINT SKYBLUE (-6000 6625);
FORCEPROP 1 LAST VOLTAGE 25V
J 0
(-6000 6775);
DISPLAY 0.489362 (-6000 6775);
PAINT SKYBLUE (-6000 6775);
FORCEPROP 1 LAST PACK_TYPE C0402
J 0
(-6000 6575);
DISPLAY 0.489362 (-6000 6575);
PAINT SKYBLUE (-6000 6575);
FORCEPROP 2 LAST CDS_LIB pure_quanta
J 0
(-6050 6775);
DISPLAY INVISIBLE (-6050 6775);
FORCEPROP 1 LAST PATH I27
J 0
(-6000 6925);
DISPLAY 0.978723 (-6000 6925);
PAINT WHITE (-6000 6925);
DISPLAY INVISIBLE (-6000 6925);
FORCEADD UNIVERSAL_GND..1
(-6050 6250);
FORCEPROP 3 LASTPIN (-6050 6300) SIG_NAME GND\g
J 0
(-6040 6310);
DISPLAY 0.659574 (-6040 6310);
PAINT MONO (-6040 6310);
DISPLAY INVISIBLE (-6040 6310);
FORCEPROP 2 LAST CDS_LIB pure_quanta_power
J 0
(-6050 6250);
DISPLAY INVISIBLE (-6050 6250);
FORCEPROP 1 LAST PATH I28
J 0
(-5975 6250);
DISPLAY 0.872340 (-5975 6250);
PAINT AQUA (-5975 6250);
DISPLAY INVISIBLE (-5975 6250);
FORCEPROP 1 LAST HDL_POWER GND
J 1
(-6025 6175);
DISPLAY 0.872340 (-6025 6175);
PAINT GREEN (-6025 6175);
DISPLAY INVISIBLE (-6025 6175);
FORCEADD UNIVERSAL_POWER..1
(-7500 7500);
FORCEPROP 3 LASTPIN (-7500 7450) SIG_NAME P3V3_STBY\g
J 0
(-7490 7460);
DISPLAY 0.659574 (-7490 7460);
PAINT MONO (-7490 7460);
DISPLAY INVISIBLE (-7490 7460);
FORCEPROP 1 LAST HDL_POWER P3V3_STBY
J 1
(-7500 7550);
DISPLAY 0.489362 (-7500 7550);
PAINT GREEN (-7500 7550);
FORCEPROP 2 LAST CDS_LIB pure_quanta_power
J 0
(-7500 7500);
DISPLAY INVISIBLE (-7500 7500);
FORCEPROP 1 LAST PATH I29
J 0
(-7450 7525);
DISPLAY 0.872340 (-7450 7525);
PAINT AQUA (-7450 7525);
DISPLAY INVISIBLE (-7450 7525);
FORCEADD UNIVERSAL_POWER..1
(-2200 6775);
FORCEPROP 3 LASTPIN (-2200 6725) SIG_NAME P1V5_BAT\g
J 0
(-2190 6735);
DISPLAY 0.659574 (-2190 6735);
PAINT MONO (-2190 6735);
DISPLAY INVISIBLE (-2190 6735);
FORCEPROP 1 LAST HDL_POWER P1V5_BAT
J 1
(-2200 6825);
DISPLAY 0.489362 (-2200 6825);
PAINT GREEN (-2200 6825);
FORCEPROP 2 LAST CDS_LIB pure_quanta_power
J 0
(-2200 6775);
DISPLAY INVISIBLE (-2200 6775);
FORCEPROP 1 LAST PATH I3
J 0
(-2150 6800);
DISPLAY 0.872340 (-2150 6800);
PAINT AQUA (-2150 6800);
DISPLAY INVISIBLE (-2150 6800);
FORCEADD SCHOTTKY_DUAL_12A_3C..1
R 5
(-7100 6975);
FORCEPROP 1 LAST LOCATION U166
J 0
(-7075 7325);
DISPLAY 0.489362 (-7075 7325);
PAINT SKYBLUE (-7075 7325);
FORCEPROP 0 LAST $SEC 1
J 0
(-7075 7375);
DISPLAY 0.680851 (-7075 7375);
PAINT MONO (-7075 7375);
DISPLAY INVISIBLE (-7075 7375);
FORCEPROP 0 LAST CDS_SEC 1
J 0
(-7075 7375);
DISPLAY 1.021277 (-7075 7375);
DISPLAY INVISIBLE (-7075 7375);
FORCEPROP 0 LASTPIN (-7200 6925) $PN 2
J 2
(-7210 6935);
DISPLAY 0.489362 (-7210 6935);
PAINT MONO (-7210 6935);
FORCEPROP 0 LASTPIN (-7200 7025) $PN 1
J 2
(-7210 7035);
DISPLAY 0.489362 (-7210 7035);
PAINT MONO (-7210 7035);
FORCEPROP 0 LASTPIN (-7000 6975) $PN 3
J 0
(-6990 6985);
DISPLAY 0.489362 (-6990 6985);
PAINT MONO (-6990 6985);
FORCEPROP 2 LAST PART_TYPE SMLF
J 0
(-7075 7250);
DISPLAY 1.021277 (-7075 7250);
FORCEPROP 1 LAST MATERIAL IC
J 0
(-7075 7100);
DISPLAY 0.489362 (-7075 7100);
PAINT SKYBLUE (-7075 7100);
FORCEPROP 2 LAST VALUE BAT54CW
J 0
(-7075 7200);
DISPLAY 0.489362 (-7075 7200);
PAINT SKYBLUE (-7075 7200);
FORCEPROP 1 LAST PART_NUMBER BCBAT54CZ13
J 0
(-7075 7150);
DISPLAY 0.489362 (-7075 7150);
PAINT SKYBLUE (-7075 7150);
FORCEPROP 2 LAST CDS_LIB pure_quanta
R 3
J 0
(-7100 6975);
DISPLAY INVISIBLE (-7100 6975);
FORCEPROP 1 LAST NEEDS_NO_SIZE TRUE
R 3
J 0
(-7110 6875);
DISPLAY 0.723404 (-7110 6875);
PAINT GREEN (-7110 6875);
DISPLAY INVISIBLE (-7110 6875);
FORCEPROP 1 LAST CDS_LMAN_SYM_OUTLINE -100,50,100,-50
R 3
J 0
(-7100 6975);
DISPLAY 0.468085 (-7100 6975);
PAINT GREEN (-7100 6975);
DISPLAY INVISIBLE (-7100 6975);
FORCEPROP 1 LAST PATH I30
R 3
J 0
(-7150 6875);
DISPLAY 0.723404 (-7150 6875);
PAINT GREEN (-7150 6875);
DISPLAY INVISIBLE (-7150 6875);
FORCEADD Q_RES..1
(-8075 6925);
FORCEPROP 1 LAST LOCATION R1775
J 0
(-8325 6925);
DISPLAY 0.489362 (-8325 6925);
PAINT SKYBLUE (-8325 6925);
FORCEPROP 2 LAST $SEC 1
J 0
(-8125 7125);
DISPLAY 0.680851 (-8125 7125);
PAINT MONO (-8125 7125);
DISPLAY INVISIBLE (-8125 7125);
FORCEPROP 2 LAST CDS_SEC 1
J 0
(-8125 7125);
DISPLAY 0.680851 (-8125 7125);
DISPLAY INVISIBLE (-8125 7125);
FORCEPROP 1 LASTPIN (-8175 6925) $PN 1
J 0
(-8163 6937);
DISPLAY 0.489362 (-8163 6937);
FORCEPROP 1 LASTPIN (-7975 6925) $PN 2
J 0
(-8013 6937);
DISPLAY 0.489362 (-8013 6937);
FORCEPROP 1 LAST WATTAGE 1/16W
J 2
(-7875 6825);
DISPLAY 0.489362 (-7875 6825);
PAINT SKYBLUE (-7875 6825);
FORCEPROP 1 LAST MATERIAL CHIP
J 0
(-8175 6825);
DISPLAY 0.489362 (-8175 6825);
PAINT SKYBLUE (-8175 6825);
FORCEPROP 1 LAST TOLERANCE 1%
J 0
(-8100 6775);
DISPLAY 0.489362 (-8100 6775);
PAINT SKYBLUE (-8100 6775);
FORCEPROP 1 LAST VALUE 1K
J 2
(-7875 6950);
DISPLAY 0.489362 (-7875 6950);
PAINT SKYBLUE (-7875 6950);
FORCEPROP 1 LAST PART_NUMBER TMP_QCS21002FB24
J 0
(-8175 6875);
DISPLAY 0.489362 (-8175 6875);
PAINT SKYBLUE (-8175 6875);
FORCEPROP 1 LAST PACK_TYPE 0402LF
J 0
(-8000 6775);
DISPLAY 0.489362 (-8000 6775);
PAINT SKYBLUE (-8000 6775);
FORCEPROP 2 LAST CDS_LIB pure_quanta
J 0
(-8075 6925);
DISPLAY INVISIBLE (-8075 6925);
FORCEPROP 1 LAST PATH I32
J 0
(-8125 7075);
DISPLAY 0.978723 (-8125 7075);
PAINT WHITE (-8125 7075);
DISPLAY INVISIBLE (-8125 7075);
FORCEADD Q_CAP..1
(-6150 4800);
FORCEPROP 1 LAST LOCATION C1563
J 0
(-6100 4925);
DISPLAY 0.489362 (-6100 4925);
PAINT SKYBLUE (-6100 4925);
FORCEPROP 2 LAST $SEC 1
J 0
(-6100 5000);
DISPLAY 0.680851 (-6100 5000);
PAINT MONO (-6100 5000);
DISPLAY INVISIBLE (-6100 5000);
FORCEPROP 2 LAST CDS_SEC 1
J 0
(-6100 5000);
DISPLAY 0.680851 (-6100 5000);
DISPLAY INVISIBLE (-6100 5000);
FORCEPROP 1 LASTPIN (-6150 4900) $PN 1
J 0
(-6140 4880);
DISPLAY 0.489362 (-6140 4880);
FORCEPROP 1 LASTPIN (-6150 4700) $PN 2
J 0
(-6140 4680);
DISPLAY 0.489362 (-6140 4680);
FORCEPROP 1 LAST MATERIAL X7R
J 0
(-6100 4725);
DISPLAY 0.489362 (-6100 4725);
PAINT SKYBLUE (-6100 4725);
FORCEPROP 1 LAST TOLERANCE 10%
J 0
(-6100 4775);
DISPLAY 0.489362 (-6100 4775);
PAINT SKYBLUE (-6100 4775);
FORCEPROP 1 LAST VALUE 0.1UF
J 0
(-6100 4875);
DISPLAY 0.489362 (-6100 4875);
PAINT SKYBLUE (-6100 4875);
FORCEPROP 1 LAST PART_NUMBER CH4103K1B08
J 0
(-6100 4675);
DISPLAY 0.489362 (-6100 4675);
PAINT SKYBLUE (-6100 4675);
FORCEPROP 1 LAST VOLTAGE 16V
J 0
(-6100 4825);
DISPLAY 0.489362 (-6100 4825);
PAINT SKYBLUE (-6100 4825);
FORCEPROP 1 LAST PACK_TYPE C0402
J 0
(-6100 4625);
DISPLAY 0.489362 (-6100 4625);
PAINT SKYBLUE (-6100 4625);
FORCEPROP 2 LAST CDS_LIB pure_quanta
J 0
(-6150 4800);
DISPLAY INVISIBLE (-6150 4800);
FORCEPROP 1 LAST PATH I35
J 0
(-6100 4950);
DISPLAY 0.978723 (-6100 4950);
PAINT WHITE (-6100 4950);
DISPLAY INVISIBLE (-6100 4950);
FORCEADD UNIVERSAL_GND..1
(-6150 4325);
FORCEPROP 3 LASTPIN (-6150 4375) SIG_NAME GND\g
J 0
(-6140 4385);
DISPLAY 0.659574 (-6140 4385);
PAINT MONO (-6140 4385);
DISPLAY INVISIBLE (-6140 4385);
FORCEPROP 2 LAST CDS_LIB pure_quanta_power
J 0
(-6150 4325);
DISPLAY INVISIBLE (-6150 4325);
FORCEPROP 1 LAST PATH I36
J 0
(-6075 4325);
DISPLAY 0.872340 (-6075 4325);
PAINT AQUA (-6075 4325);
DISPLAY INVISIBLE (-6075 4325);
FORCEPROP 1 LAST HDL_POWER GND
J 1
(-6125 4250);
DISPLAY 0.872340 (-6125 4250);
PAINT GREEN (-6125 4250);
DISPLAY INVISIBLE (-6125 4250);
FORCEADD Q_RES..2
(-6600 4800);
FORCEPROP 1 LAST LOCATION R1776
J 0
(-6555 4925);
DISPLAY 0.489362 (-6555 4925);
PAINT SKYBLUE (-6555 4925);
FORCEPROP 0 LAST $SEC 1
J 0
(-6550 4975);
DISPLAY 0.680851 (-6550 4975);
PAINT MONO (-6550 4975);
DISPLAY INVISIBLE (-6550 4975);
FORCEPROP 0 LAST CDS_SEC 1
J 0
(-6550 4975);
DISPLAY 1.021277 (-6550 4975);
DISPLAY INVISIBLE (-6550 4975);
FORCEPROP 1 LASTPIN (-6600 4900) $PN 1
J 0
(-6595 4862);
DISPLAY 0.489362 (-6595 4862);
PAINT MONO (-6595 4862);
FORCEPROP 1 LASTPIN (-6600 4700) $PN 2
J 0
(-6595 4710);
DISPLAY 0.489362 (-6595 4710);
PAINT MONO (-6595 4710);
FORCEPROP 1 LAST WATTAGE 1/16W
J 0
(-6560 4775);
DISPLAY 0.489362 (-6560 4775);
PAINT SKYBLUE (-6560 4775);
FORCEPROP 1 LAST MATERIAL CHIP
J 0
(-6560 4725);
DISPLAY 0.489362 (-6560 4725);
PAINT SKYBLUE (-6560 4725);
FORCEPROP 1 LAST TOLERANCE 1%
J 0
(-6555 4825);
DISPLAY 0.489362 (-6555 4825);
PAINT SKYBLUE (-6555 4825);
FORCEPROP 1 LAST VALUE 1K
J 0
(-6555 4875);
DISPLAY 0.489362 (-6555 4875);
PAINT SKYBLUE (-6555 4875);
FORCEPROP 1 LAST PART_NUMBER TMP_QCS21002FB24
J 0
(-6560 4675);
DISPLAY 0.489362 (-6560 4675);
PAINT SKYBLUE (-6560 4675);
FORCEPROP 1 LAST PACK_TYPE 0402LF
J 0
(-6560 4625);
DISPLAY 0.489362 (-6560 4625);
PAINT SKYBLUE (-6560 4625);
FORCEPROP 2 LAST BOM_COST VR_SYSTEM 
J 0
(-6550 4975);
DISPLAY 0.680851 (-6550 4975);
DISPLAY INVISIBLE (-6550 4975);
FORCEPROP 2 LAST CDS_LIB pure_quanta
J 0
(-6600 4800);
DISPLAY INVISIBLE (-6600 4800);
FORCEPROP 1 LAST PATH I37
J 0
(-6550 4975);
DISPLAY 0.978723 (-6550 4975);
PAINT WHITE (-6550 4975);
DISPLAY INVISIBLE (-6550 4975);
FORCEADD OFFPAGE..1
(-7000 5000);
FORCEPROP 2 LAST $XR0 81 
J 0
(-7251 5000);
DISPLAY 0.638298 (-7251 5000);
PAINT MONO (-7251 5000);
FORCEPROP 2 LAST CDS_LIB standard
J 0
(-7000 5000);
DISPLAY INVISIBLE (-7000 5000);
FORCEPROP 1 LAST OFFPAGE TRUE
J 0
(-6675 4875);
DISPLAY 0.872340 (-6675 4875);
PAINT GREEN (-6675 4875);
DISPLAY INVISIBLE (-6675 4875);
FORCEPROP 1 LAST COMMENT_BODY TRUE
J 0
(-6875 4900);
DISPLAY 0.872340 (-6875 4900);
PAINT GREEN (-6875 4900);
DISPLAY INVISIBLE (-6875 4900);
FORCEPROP 2 LAST PATH I38
J 0
(-7200 5050);
DISPLAY 0.680851 (-7200 5050);
DISPLAY INVISIBLE (-7200 5050);
FORCEADD CONN2_AAABAT029P15..1
R 2
(-9025 6925);
FORCEPROP 1 LAST LOCATION BT2
J 2
(-8975 7100);
DISPLAY 0.489362 (-8975 7100);
PAINT SKYBLUE (-8975 7100);
FORCEPROP 0 LAST $SEC 1
J 2
(-8975 7300);
DISPLAY 0.680851 (-8975 7300);
PAINT MONO (-8975 7300);
DISPLAY INVISIBLE (-8975 7300);
FORCEPROP 0 LAST CDS_SEC 1
J 2
(-8975 7300);
DISPLAY 1.021277 (-8975 7300);
DISPLAY INVISIBLE (-8975 7300);
FORCEPROP 0 LASTPIN (-8925 6925) $PN 1
J 0
(-8915 6935);
DISPLAY 0.489362 (-8915 6935);
PAINT MONO (-8915 6935);
FORCEPROP 0 LASTPIN (-9125 6925) $PN 2
J 2
(-9135 6935);
DISPLAY 0.489362 (-9135 6935);
PAINT MONO (-9135 6935);
FORCEPROP 2 LAST PART_TYPE THLF
J 2
(-8950 7200);
DISPLAY 1.021277 (-8950 7200);
FORCEPROP 1 LAST MATERIAL IO
J 2
(-8975 7025);
DISPLAY 0.489362 (-8975 7025);
PAINT SKYBLUE (-8975 7025);
FORCEPROP 2 LAST VALUE CONN2_AAA-BAT-029-P15
J 2
(-8975 7150);
DISPLAY 0.489362 (-8975 7150);
PAINT SKYBLUE (-8975 7150);
FORCEPROP 1 LAST PART_NUMBER DFHS02FR031
J 2
(-8966 7065);
DISPLAY 0.489362 (-8966 7065);
PAINT SKYBLUE (-8966 7065);
FORCEPROP 1 LAST CDS_LMAN_SYM_OUTLINE -50,50,50,-50
J 2
(-9025 6925);
DISPLAY 0.468085 (-9025 6925);
PAINT GREEN (-9025 6925);
DISPLAY INVISIBLE (-9025 6925);
FORCEPROP 1 LAST NEEDS_NO_SIZE TRUE
J 2
(-9025 6925);
DISPLAY 0.723404 (-9025 6925);
PAINT GREEN (-9025 6925);
DISPLAY INVISIBLE (-9025 6925);
FORCEPROP 2 LAST CDS_LIB pure_quanta
J 2
(-9025 6925);
DISPLAY INVISIBLE (-9025 6925);
FORCEPROP 1 LAST PATH I39
J 2
(-9025 6925);
DISPLAY 0.723404 (-9025 6925);
PAINT GREEN (-9025 6925);
DISPLAY INVISIBLE (-9025 6925);
FORCEADD Q_CAP..1
(-1975 6250);
FORCEPROP 1 LAST LOCATION C1567
J 0
(-1925 6350);
DISPLAY 0.489362 (-1925 6350);
PAINT SKYBLUE (-1925 6350);
FORCEPROP 0 LAST $SEC 1
J 0
(-1925 6400);
DISPLAY 0.680851 (-1925 6400);
PAINT MONO (-1925 6400);
DISPLAY INVISIBLE (-1925 6400);
FORCEPROP 0 LAST CDS_SEC 1
J 0
(-1925 6400);
DISPLAY 1.021277 (-1925 6400);
DISPLAY INVISIBLE (-1925 6400);
FORCEPROP 1 LASTPIN (-1975 6350) $PN 1
J 0
(-1965 6330);
DISPLAY 0.489362 (-1965 6330);
PAINT MONO (-1965 6330);
FORCEPROP 1 LASTPIN (-1975 6150) $PN 2
J 0
(-1965 6130);
DISPLAY 0.489362 (-1965 6130);
PAINT MONO (-1965 6130);
FORCEPROP 1 LAST MATERIAL X6S
J 0
(-1925 6150);
DISPLAY 0.489362 (-1925 6150);
PAINT SKYBLUE (-1925 6150);
FORCEPROP 1 LAST TOLERANCE 10%
J 0
(-1925 6200);
DISPLAY 0.489362 (-1925 6200);
PAINT SKYBLUE (-1925 6200);
FORCEPROP 1 LAST VALUE 1UF
J 0
(-1925 6300);
DISPLAY 0.489362 (-1925 6300);
PAINT SKYBLUE (-1925 6300);
FORCEPROP 1 LAST PART_NUMBER CH5104KEB02
J 0
(-1925 6100);
DISPLAY 0.489362 (-1925 6100);
PAINT SKYBLUE (-1925 6100);
FORCEPROP 1 LAST VOLTAGE 25V
J 0
(-1925 6250);
DISPLAY 0.489362 (-1925 6250);
PAINT SKYBLUE (-1925 6250);
FORCEPROP 1 LAST PACK_TYPE C0402
J 0
(-1925 6050);
DISPLAY 0.489362 (-1925 6050);
PAINT SKYBLUE (-1925 6050);
FORCEPROP 2 LAST CDS_LIB pure_quanta
J 0
(-1975 6250);
DISPLAY INVISIBLE (-1975 6250);
FORCEPROP 1 LAST PATH I4
J 0
(-1925 6400);
DISPLAY 0.978723 (-1925 6400);
PAINT WHITE (-1925 6400);
DISPLAY INVISIBLE (-1925 6400);
FORCEADD GND..1
(-9300 6425);
FORCEPROP 3 LASTPIN (-9300 6475) SIG_NAME GND\g
J 0
(-9290 6485);
DISPLAY 0.659574 (-9290 6485);
PAINT MONO (-9290 6485);
DISPLAY INVISIBLE (-9290 6485);
FORCEPROP 1 LAST SIZE 1B
J 0
(-9225 6375);
DISPLAY 1.170213 (-9225 6375);
PAINT AQUA (-9225 6375);
DISPLAY INVISIBLE (-9225 6375);
FORCEPROP 2 LAST CDS_LIB pure_quanta_power
J 0
(-9300 6425);
DISPLAY INVISIBLE (-9300 6425);
FORCEPROP 1 LAST PATH I40
J 0
(-9225 6425);
DISPLAY 0.872340 (-9225 6425);
PAINT AQUA (-9225 6425);
DISPLAY INVISIBLE (-9225 6425);
FORCEPROP 1 LAST HDL_POWER GND
J 0
(-9300 6575);
DISPLAY 1.170213 (-9300 6575);
PAINT GREEN (-9300 6575);
DISPLAY INVISIBLE (-9300 6575);
FORCEADD MOSFET_DUAL_6P..1
(-5200 5000);
FORCEPROP 1 LAST LOCATION Q8
J 0
(-5347 5209);
DISPLAY 0.489362 (-5347 5209);
PAINT SKYBLUE (-5347 5209);
FORCEPROP 2 LAST $SEC 1
J 0
(-5325 5350);
DISPLAY 0.680851 (-5325 5350);
PAINT MONO (-5325 5350);
DISPLAY INVISIBLE (-5325 5350);
FORCEPROP 2 LAST CDS_SEC 1
J 0
(-5325 5350);
DISPLAY 0.680851 (-5325 5350);
DISPLAY INVISIBLE (-5325 5350);
FORCEPROP 2 LASTPIN (-5500 4950) $PN 6
J 2
(-5510 4960);
DISPLAY 0.489362 (-5510 4960);
PAINT MONO (-5510 4960);
FORCEPROP 2 LASTPIN (-4900 4950) $PN 3
J 0
(-4890 4960);
DISPLAY 0.489362 (-4890 4960);
PAINT MONO (-4890 4960);
FORCEPROP 2 LASTPIN (-5500 5000) $PN 2
J 2
(-5510 5010);
DISPLAY 0.489362 (-5510 5010);
PAINT MONO (-5510 5010);
FORCEPROP 2 LASTPIN (-4900 5000) $PN 5
J 0
(-4890 5010);
DISPLAY 0.489362 (-4890 5010);
PAINT MONO (-4890 5010);
FORCEPROP 2 LASTPIN (-5500 5050) $PN 1
J 2
(-5510 5060);
DISPLAY 0.489362 (-5510 5060);
PAINT MONO (-5510 5060);
FORCEPROP 2 LASTPIN (-4900 5050) $PN 4
J 0
(-4890 5060);
DISPLAY 0.489362 (-4890 5060);
PAINT MONO (-4890 5060);
FORCEPROP 2 LAST PART_TYPE SMLF
J 0
(-5325 5300);
DISPLAY 0.680851 (-5325 5300);
FORCEPROP 1 LAST MATERIAL IC
J 0
(-5347 5123);
DISPLAY 0.489362 (-5347 5123);
PAINT SKYBLUE (-5347 5123);
FORCEPROP 2 LAST VALUE 2N7002KDW
J 0
(-5325 5250);
DISPLAY 0.489362 (-5325 5250);
PAINT SKYBLUE (-5325 5250);
FORCEPROP 1 LAST PART_NUMBER BAM70020047
J 0
(-5347 5167);
DISPLAY 0.489362 (-5347 5167);
PAINT SKYBLUE (-5347 5167);
FORCEPROP 1 LAST CDS_LMAN_SYM_OUTLINE -150,100,150,-100
J 0
(-5200 5000);
DISPLAY 0.468085 (-5200 5000);
PAINT GREEN (-5200 5000);
DISPLAY INVISIBLE (-5200 5000);
FORCEPROP 1 LAST NEEDS_NO_SIZE TRUE
J 0
(-5200 4999);
DISPLAY 0.468085 (-5200 4999);
PAINT GREEN (-5200 4999);
DISPLAY INVISIBLE (-5200 4999);
FORCEPROP 2 LAST CDS_LIB pure_quanta
J 0
(-5200 5000);
DISPLAY INVISIBLE (-5200 5000);
FORCEPROP 1 LAST PATH I41
J 0
(-5200 5000);
DISPLAY 0.723404 (-5200 5000);
PAINT GREEN (-5200 5000);
DISPLAY INVISIBLE (-5200 5000);
FORCEADD UNIVERSAL_GND..1
R 1
(-4850 5050);
FORCEPROP 3 LASTPIN (-4900 5050) SIG_NAME GND\g
J 0
(-4890 5060);
DISPLAY 0.659574 (-4890 5060);
PAINT MONO (-4890 5060);
DISPLAY INVISIBLE (-4890 5060);
FORCEPROP 2 LAST CDS_LIB pure_quanta_power
R 1
J 0
(-4850 5050);
DISPLAY INVISIBLE (-4850 5050);
FORCEPROP 1 LAST PATH I42
R 1
J 0
(-4850 5125);
DISPLAY 0.872340 (-4850 5125);
PAINT AQUA (-4850 5125);
DISPLAY INVISIBLE (-4850 5125);
FORCEPROP 1 LAST HDL_POWER GND
R 1
J 1
(-4775 5075);
DISPLAY 0.872340 (-4775 5075);
PAINT GREEN (-4775 5075);
DISPLAY INVISIBLE (-4775 5075);
FORCEADD UNIVERSAL_GND..1
R 5
(-5550 5050);
FORCEPROP 3 LASTPIN (-5500 5050) SIG_NAME GND\g
J 0
(-5490 5060);
DISPLAY 0.659574 (-5490 5060);
PAINT MONO (-5490 5060);
DISPLAY INVISIBLE (-5490 5060);
FORCEPROP 2 LAST CDS_LIB pure_quanta_power
R 3
J 0
(-5550 5050);
DISPLAY INVISIBLE (-5550 5050);
FORCEPROP 1 LAST PATH I43
R 3
J 0
(-5550 4975);
DISPLAY 0.872340 (-5550 4975);
PAINT AQUA (-5550 4975);
DISPLAY INVISIBLE (-5550 4975);
FORCEPROP 1 LAST HDL_POWER GND
R 3
J 1
(-5625 5025);
DISPLAY 0.872340 (-5625 5025);
PAINT GREEN (-5625 5025);
DISPLAY INVISIBLE (-5625 5025);
FORCEADD TP..1
(-1250 7550);
FORCEPROP 1 LAST LOCATION JP12_12
J 1
(-1245 7570);
DISPLAY 0.489362 (-1245 7570);
PAINT SKYBLUE (-1245 7570);
FORCEPROP 0 LAST $SEC 1
J 0
(-1225 7600);
DISPLAY 0.680851 (-1225 7600);
PAINT MONO (-1225 7600);
DISPLAY INVISIBLE (-1225 7600);
FORCEPROP 0 LAST CDS_SEC 1
J 0
(-1225 7600);
DISPLAY 0.680851 (-1225 7600);
DISPLAY INVISIBLE (-1225 7600);
FORCEPROP 0 LASTPIN (-1250 7500) $PN 1
R 1
J 2
(-1260 7490);
DISPLAY 0.489362 (-1260 7490);
PAINT MONO (-1260 7490);
FORCEPROP 1 LAST MATERIAL EMPTY
J 0
(-1225 7475);
DISPLAY 0.489362 (-1225 7475);
PAINT RED (-1225 7475);
FORCEPROP 2 LAST CDS_LIB pure_quanta
J 0
(-1250 7550);
DISPLAY INVISIBLE (-1250 7550);
FORCEPROP 1 LASTPIN (-1250 7500) $PIN_NUMBER ?
J 2
(-1200 7500);
DISPLAY 0.702128 (-1200 7500);
PAINT MONO (-1200 7500);
DISPLAY INVISIBLE (-1200 7500);
FORCEPROP 1 LAST PATH I45
J 1
(-1245 7595);
DISPLAY 0.446809 (-1245 7595);
PAINT GREEN (-1245 7595);
DISPLAY INVISIBLE (-1245 7595);
FORCEPROP 1 LAST PART_NUMBER TP26
J 1
(-1195 7505);
DISPLAY 0.446809 (-1195 7505);
PAINT SKYBLUE (-1195 7505);
DISPLAY INVISIBLE (-1195 7505);
FORCEPROP 1 LAST PACK_TYPE TP
J 1
(-1195 7485);
DISPLAY 0.446809 (-1195 7485);
PAINT SKYBLUE (-1195 7485);
DISPLAY INVISIBLE (-1195 7485);
FORCEADD TP..1
(-9050 7525);
FORCEPROP 1 LAST LOCATION BATTERY_BT2
J 1
(-9045 7545);
DISPLAY 0.489362 (-9045 7545);
PAINT SKYBLUE (-9045 7545);
FORCEPROP 0 LAST $SEC 1
J 0
(-9025 7575);
DISPLAY 0.680851 (-9025 7575);
PAINT MONO (-9025 7575);
DISPLAY INVISIBLE (-9025 7575);
FORCEPROP 0 LAST CDS_SEC 1
J 0
(-9025 7575);
DISPLAY 0.680851 (-9025 7575);
DISPLAY INVISIBLE (-9025 7575);
FORCEPROP 0 LASTPIN (-9050 7475) $PN 1
R 1
J 2
(-9060 7465);
DISPLAY 0.489362 (-9060 7465);
PAINT MONO (-9060 7465);
FORCEPROP 1 LAST MATERIAL EMPTY
J 0
(-9025 7450);
DISPLAY 0.489362 (-9025 7450);
PAINT RED (-9025 7450);
FORCEPROP 1 LASTPIN (-9050 7475) $PIN_NUMBER ?
J 2
(-9000 7475);
DISPLAY 0.702128 (-9000 7475);
PAINT MONO (-9000 7475);
DISPLAY INVISIBLE (-9000 7475);
FORCEPROP 2 LAST CDS_LIB pure_quanta
J 0
(-9050 7525);
DISPLAY INVISIBLE (-9050 7525);
FORCEPROP 1 LAST PATH I46
J 1
(-9045 7570);
DISPLAY 0.446809 (-9045 7570);
PAINT GREEN (-9045 7570);
DISPLAY INVISIBLE (-9045 7570);
FORCEPROP 1 LAST PART_NUMBER TP26
J 1
(-8995 7480);
DISPLAY 0.446809 (-8995 7480);
PAINT SKYBLUE (-8995 7480);
DISPLAY INVISIBLE (-8995 7480);
FORCEPROP 1 LAST PACK_TYPE TP
J 1
(-8995 7460);
DISPLAY 0.446809 (-8995 7460);
PAINT SKYBLUE (-8995 7460);
DISPLAY INVISIBLE (-8995 7460);
FORCEADD UNIVERSAL_GND..1
(-1975 5900);
FORCEPROP 3 LASTPIN (-1975 5950) SIG_NAME GND\g
J 0
(-1965 5960);
DISPLAY 0.659574 (-1965 5960);
PAINT MONO (-1965 5960);
DISPLAY INVISIBLE (-1965 5960);
FORCEPROP 2 LAST CDS_LIB pure_quanta_power
J 0
(-1975 5900);
DISPLAY INVISIBLE (-1975 5900);
FORCEPROP 1 LAST PATH I5
J 0
(-1900 5900);
DISPLAY 0.872340 (-1900 5900);
PAINT AQUA (-1900 5900);
DISPLAY INVISIBLE (-1900 5900);
FORCEPROP 1 LAST HDL_POWER GND
J 1
(-1950 5825);
DISPLAY 0.872340 (-1950 5825);
PAINT GREEN (-1950 5825);
DISPLAY INVISIBLE (-1950 5825);
FORCEADD Q_CAP..1
(-3175 6750);
FORCEPROP 1 LAST LOCATION C1564
J 0
(-3125 6850);
DISPLAY 0.489362 (-3125 6850);
PAINT SKYBLUE (-3125 6850);
FORCEPROP 2 LAST $SEC 1
J 0
(-3125 6950);
DISPLAY 0.680851 (-3125 6950);
PAINT MONO (-3125 6950);
DISPLAY INVISIBLE (-3125 6950);
FORCEPROP 2 LAST CDS_SEC 1
J 0
(-3125 6950);
DISPLAY 0.680851 (-3125 6950);
DISPLAY INVISIBLE (-3125 6950);
FORCEPROP 1 LASTPIN (-3175 6850) $PN 1
J 0
(-3165 6830);
DISPLAY 0.489362 (-3165 6830);
FORCEPROP 1 LASTPIN (-3175 6650) $PN 2
J 0
(-3165 6630);
DISPLAY 0.489362 (-3165 6630);
FORCEPROP 1 LAST MATERIAL X6S
J 0
(-3125 6650);
DISPLAY 0.489362 (-3125 6650);
PAINT SKYBLUE (-3125 6650);
FORCEPROP 1 LAST TOLERANCE 10%
J 0
(-3125 6700);
DISPLAY 0.489362 (-3125 6700);
PAINT SKYBLUE (-3125 6700);
FORCEPROP 1 LAST VALUE 1UF
J 0
(-3125 6800);
DISPLAY 0.489362 (-3125 6800);
PAINT SKYBLUE (-3125 6800);
FORCEPROP 1 LAST PART_NUMBER CH5104KEB02
J 0
(-3125 6600);
DISPLAY 0.489362 (-3125 6600);
PAINT SKYBLUE (-3125 6600);
FORCEPROP 1 LAST VOLTAGE 25V
J 0
(-3125 6750);
DISPLAY 0.489362 (-3125 6750);
PAINT SKYBLUE (-3125 6750);
FORCEPROP 1 LAST PACK_TYPE C0402
J 0
(-3125 6550);
DISPLAY 0.489362 (-3125 6550);
PAINT SKYBLUE (-3125 6550);
FORCEPROP 2 LAST CDS_LIB pure_quanta
J 0
(-3175 6750);
DISPLAY INVISIBLE (-3175 6750);
FORCEPROP 1 LAST PATH I6
J 0
(-3125 6900);
DISPLAY 0.978723 (-3125 6900);
PAINT WHITE (-3125 6900);
DISPLAY INVISIBLE (-3125 6900);
FORCEADD UNIVERSAL_GND..1
(-3175 6375);
FORCEPROP 3 LASTPIN (-3175 6425) SIG_NAME GND\g
J 0
(-3165 6435);
DISPLAY 0.659574 (-3165 6435);
PAINT MONO (-3165 6435);
DISPLAY INVISIBLE (-3165 6435);
FORCEPROP 2 LAST CDS_LIB pure_quanta_power
J 0
(-3175 6375);
DISPLAY INVISIBLE (-3175 6375);
FORCEPROP 1 LAST PATH I7
J 0
(-3100 6375);
DISPLAY 0.872340 (-3100 6375);
PAINT AQUA (-3100 6375);
DISPLAY INVISIBLE (-3100 6375);
FORCEPROP 1 LAST HDL_POWER GND
J 1
(-3150 6300);
DISPLAY 0.872340 (-3150 6300);
PAINT GREEN (-3150 6300);
DISPLAY INVISIBLE (-3150 6300);
FORCEADD QUANTA_TITLE_BLOCK_C..1
(-200 1950);
FORCEPROP 0 LAST CDS_CON_LAST_MODIFIED Fri Mar 11 14:53:18 2022
J 0
(-2085 1965);
DISPLAY INVISIBLE (-2085 1965);
FORCEPROP 1 LAST CUSTOM_TXT_CDS <CON_LAST_MODIFIED>
J 0
(-2085 1965);
DISPLAY 0.978723 (-2085 1965);
FORCEPROP 2 LAST CUSTOM_TXT_CDS <XR_PAGE_TITLE>
J 0
(-8090 7200);
DISPLAY 0.638298 (-8090 7200);
PAINT PINK (-8090 7200);
DISPLAY INVISIBLE (-8090 7200);
FORCEPROP 1 LAST CUSTOM_TXT_CDS <NAME_2>
J 0
(-3375 2000);
FORCEPROP 1 LAST CUSTOM_TXT_CDS <NAME_1>
J 0
(-3375 2125);
FORCEPROP 1 LAST CUSTOM_TXT_CDS <Q_NUMBER>
J 0
(-1603 2053);
DISPLAY 1.212766 (-1603 2053);
FORCEPROP 1 LAST CUSTOM_TXT_CDS <Q_PROJ>
J 0
(-2582 2052);
DISPLAY 1.212766 (-2582 2052);
FORCEPROP 1 LAST CUSTOM_TXT_CDS <Q_REV>
J 0
(-384 2053);
DISPLAY 1.212766 (-384 2053);
FORCEPROP 1 LAST CUSTOM_TXT_CDS <CON_PAGE_NUM> OF <CON_TOTAL_PAGES>
J 0
(-646 1968);
DISPLAY 0.978723 (-646 1968);
FORCEPROP 1 LAST Q_DEPT BU9
J 1
(-3963 1999);
DISPLAY 1.957447 (-3963 1999);
PAINT GREEN (-3963 1999);
FORCEPROP 1 LAST Q_TITLE BATTERY
J 0
(-9450 2025);
DISPLAY 2.446809 (-9450 2025);
PAINT GREEN (-9450 2025);
FORCEPROP 2 LAST CDS_LIB pure_quanta
J 0
(-200 1950);
DISPLAY INVISIBLE (-200 1950);
FORCEPROP 1 LAST CDS_LMAN_SYM_OUTLINE -9475,6775,100,-125
J 0
(-200 1950);
DISPLAY 0.468085 (-200 1950);
PAINT GREEN (-200 1950);
DISPLAY INVISIBLE (-200 1950);
FORCEPROP 2 LAST PAGE_BORDER TRUE
J 0
(-8090 7200);
DISPLAY 0.638298 (-8090 7200);
PAINT PINK (-8090 7200);
DISPLAY INVISIBLE (-8090 7200);
FORCEPROP 1 LAST COMMENT_BODY TRUE
J 0
(-188 1937);
DISPLAY 0.978723 (-188 1937);
PAINT GREEN (-188 1937);
DISPLAY INVISIBLE (-188 1937);
FORCEPROP 2 LAST CDS_XR_PAGE_TITLE CR-156 : @T6G_MB_LIB.T6G(SCH_1):PAGE156
J 0
(-8090 7200);
DISPLAY 0.638298 (-8090 7200);
PAINT PINK (-8090 7200);
DISPLAY INVISIBLE (-8090 7200);
WIRE 16 -1 (-1700 7525)(-1800 7525);
WIRE 16 -1 (-1800 7525)(-1800 7350);
WIRE 16 -1 (-4550 6825)(-4575 6825);
WIRE 16 -1 (-4575 6825)(-4575 6625);
WIRE 16 -1 (-7500 7025)(-7500 7450);
WIRE 16 -1 (-7200 7025)(-7500 7025);
WIRE 16 -1 (-9125 6925)(-9300 6925);
WIRE 16 -1 (-9300 6925)(-9300 6475);
WIRE 16 -1 (-1975 5950)(-1975 6150);
WIRE 16 -1 (-3175 6425)(-3175 6650);
WIRE 16 -1 (-8925 6925)(-8175 6925);
FORCEPROP 2 LAST SIG_NAME P3V_BAT
J 0
(-8710 6935);
DISPLAY 0.489362 (-8710 6935);
FORCEPROP 2 LASTPROP $XRERR UNIQUE?
J 0
(-8950 6935);
DISPLAY 0.638298 (-8950 6935);
PAINT MONO (-8950 6935);
DISPLAY INVISIBLE (-8950 6935);
WIRE 16 -1 (-6150 4375)(-6150 4575);
WIRE 16 -1 (-6150 4575)(-6150 4700);
WIRE 16 -1 (-6150 4575)(-6600 4575);
WIRE 16 -1 (-6600 4575)(-6600 4700);
WIRE 16 -1 (-6600 5000)(-6150 5000);
WIRE 16 -1 (-6600 4900)(-6600 5000);
WIRE 16 -1 (-6600 5000)(-6950 5000);
FORCEPROP 2 LAST SIG_NAME CLR_CMOS
J 0
(-6860 5010);
DISPLAY 0.489362 (-6860 5010);
WIRE 16 -1 (-6150 5000)(-5700 5000);
WIRE 16 -1 (-6150 5000)(-6150 4900);
WIRE 16 -1 (-5700 5000)(-5500 5000);
WIRE 16 -1 (-5700 4650)(-5700 5000);
WIRE 16 -1 (-4650 4650)(-5700 4650);
WIRE 16 -1 (-4650 5000)(-4650 4650);
WIRE 16 -1 (-4900 5000)(-4650 5000);
WIRE 16 -1 (-7975 6925)(-7200 6925);
FORCEPROP 2 LAST SIG_NAME P3V_BAT_R
J 0
(-7810 6935);
DISPLAY 0.489362 (-7810 6935);
FORCEPROP 2 LASTPROP $XRERR UNIQUE?
J 0
(-8050 6935);
DISPLAY 0.638298 (-8050 6935);
PAINT MONO (-8050 6935);
DISPLAY INVISIBLE (-8050 6935);
WIRE 16 -1 (-5500 4950)(-5525 4950);
WIRE 16 -1 (-5525 4950)(-5525 4775);
WIRE 16 -1 (-5525 4775)(-3450 4775);
WIRE 16 -1 (-3450 4775)(-3450 5675);
WIRE 16 -1 (-3450 5675)(-2975 5675);
FORCEPROP 2 LAST SIG_NAME CLR_CMOS_N
J 0
(-3435 5685);
DISPLAY 0.489362 (-3435 5685);
FORCEPROP 2 LASTPROP $XRERR UNIQUE?
J 0
(-3675 5685);
DISPLAY 0.638298 (-3675 5685);
PAINT MONO (-3675 5685);
DISPLAY INVISIBLE (-3675 5685);
WIRE 16 -1 (-4725 4950)(-4725 5875);
WIRE 16 -1 (-4725 4950)(-4900 4950);
WIRE 16 -1 (-4725 5875)(-3625 5875);
FORCEPROP 2 LAST SIG_NAME BAT_LDO_EN
J 0
(-4185 5885);
DISPLAY 0.489362 (-4185 5885);
FORCEPROP 2 LASTPROP $XRERR UNIQUE?
J 0
(-4425 5885);
DISPLAY 0.638298 (-4425 5885);
PAINT MONO (-4425 5885);
DISPLAY INVISIBLE (-4425 5885);
WIRE 16 -1 (-4725 6225)(-4725 5875);
WIRE 16 -1 (-3625 5875)(-3625 6825);
WIRE 16 -1 (-3625 6825)(-3850 6825);
WIRE 16 -1 (-7000 6975)(-6050 6975);
WIRE 16 -1 (-5850 6975)(-6050 6975);
WIRE 16 -1 (-6050 6975)(-6050 6875);
WIRE 16 -1 (-5850 6975)(-5850 7375);
WIRE 16 -1 (-5600 6975)(-5850 6975);
WIRE 16 -1 (-5600 6975)(-4725 6975);
WIRE 16 -1 (-5600 6875)(-5600 6975);
WIRE 16 -1 (-4725 6975)(-4550 6975);
WIRE 16 -1 (-4725 6425)(-4725 6975);
WIRE 16 -1 (-6050 6450)(-5600 6450);
WIRE 16 -1 (-6050 6675)(-6050 6450);
WIRE 16 -1 (-6050 6450)(-6050 6300);
WIRE 16 -1 (-5600 6450)(-5600 6675);
WIRE 16 -1 (-2775 5675)(-2200 5675);
WIRE 16 -1 (-2200 6450)(-2200 5675);
WIRE 16 -1 (-1975 6450)(-2200 6450);
WIRE 16 -1 (-2200 6725)(-2200 6450);
WIRE 16 -1 (-1975 7575)(-1975 6450);
WIRE 16 -1 (-1975 6450)(-1975 6350);
WIRE 16 -1 (-1700 7575)(-1975 7575);
WIRE 16 -1 (-3850 6975)(-3175 6975);
FORCEPROP 2 LAST SIG_NAME P1V5_BAT_OUT
J 0
(-3510 6985);
DISPLAY 0.489362 (-3510 6985);
FORCEPROP 2 LASTPROP $XRERR UNIQUE?
J 0
(-3750 6985);
DISPLAY 0.638298 (-3750 6985);
PAINT MONO (-3750 6985);
DISPLAY INVISIBLE (-3750 6985);
WIRE 16 -1 (-2475 6975)(-3175 6975);
WIRE 16 -1 (-3175 6975)(-3175 6850);
WIRE 16 -1 (-2475 6975)(-2475 7625);
WIRE 16 -1 (-1700 7625)(-2475 7625);
FORCEPROP 0 LAST CDS_PHYS_NET_NAME P1V5_BAT_OUT
J 2
(-1725 7667);
PAINT MONO (-1725 7667);
DISPLAY INVISIBLE (-1725 7667);
DOT 1 (-1975 6450);
DOT 1 (-2200 6450);
DOT 1 (-3175 6975);
DOT 1 (-5600 6975);
DOT 1 (-5850 6975);
DOT 1 (-6050 6975);
DOT 1 (-6050 6450);
DOT 1 (-6150 5000);
DOT 1 (-6600 5000);
DOT 1 (-6150 4575);
DOT 1 (-5700 5000);
DOT 1 (-4725 5875);
DOT 1 (-4725 6975);
FORCENOTE
CLEAR CMOS JUMPER
(-3625 8300) 0;
DISPLAY LEFT (-3625 8300);
DISPLAY 1.595745 (-3625 8300);
FORCENOTE
1-2 NORMAL OPERATION(DEFAULT)
(-3625 8175) 0;
DISPLAY LEFT (-3625 8175);
DISPLAY 1.595745 (-3625 8175);
FORCENOTE
2-3 BIOS LOAD DEFAULT
(-3625 8050) 0;
DISPLAY LEFT (-3625 8050);
DISPLAY 1.595745 (-3625 8050);
FORCENOTE
DEJP0020021
(-1275 7400) 0;
DISPLAY LEFT (-1275 7400);
DISPLAY 1.021277 (-1275 7400);
PAINT WHITE (-1275 7400);
FORCENOTE
FPGA
(-6925 5175) 0;
DISPLAY LEFT (-6925 5175);
DISPLAY 2.000000 (-6925 5175);
PAINT WHITE (-6925 5175);
FORCENOTE
AHL03003097
(-9050 7350) 0;
DISPLAY LEFT (-9050 7350);
DISPLAY 1.021277 (-9050 7350);
PAINT WHITE (-9050 7350);
QUIT
